# T6G (Grand Teton) — schematic netlist excerpt (pin names and nets, part order shuffled) for the footprints in the layout excerpt that follows; sources: Cadence DE-HDL packaged netlist, KiCad conversion of 04192023_DAF0TMB3IC0_F0TG_MB_C_brd_V02_OCP.brd

C7026  Q_CAPP  470UF 2.5V 20% SPCAP  pkg SMLF  page 345 : A = P0V9_CPU1_RT2_2A ; B = GND
C109  Q_CAP  1000PF 50V 5% X7R  pkg 0402  page 361 : A = FM_PWRGD_P1V8_RETIMER_CPU1 ; B = GND

(kicad_pcb
	(version 20260206)
	(generator "pcbnew")
	(generator_version "10.0")
	(general
		(thickness 1.6)
		(legacy_teardrops no)
	)
	(paper "A4")
	(title_block
		(title "04192023_DAF0TMB3IC0_F0TG_MB_C_brd_V02_OCP.brd")
		(comment 1 "Grand Teton / footprints 7507-7508 of 8354")
	)
	(layers
		(0 "F.Cu" signal "TOP")
		(4 "In1.Cu" signal "GND")
		(6 "In2.Cu" signal "IN1")
		(8 "In3.Cu" signal "GND1")
		(10 "In4.Cu" signal "IN2")
		(12 "In5.Cu" signal "GND2")
		(14 "In6.Cu" signal "IN3")
		(16 "In7.Cu" signal "GND3")
		(18 "In8.Cu" signal "VCC")
		(20 "In9.Cu" signal "VCC1")
		(22 "In10.Cu" signal "GND4")
		(24 "In11.Cu" signal "IN4")
		(26 "In12.Cu" signal "GND5")
		(28 "In13.Cu" signal "IN5")
		(30 "In14.Cu" signal "GND6")
		(32 "In15.Cu" signal "IN6")
		(34 "In16.Cu" signal "GND7")
		(2 "B.Cu" signal "BOTTOM")
		(9 "F.Adhes" user "F.Adhesive")
		(11 "B.Adhes" user "B.Adhesive")
		(13 "F.Paste" user "Package Geometry/Pastemask Top")
		(15 "B.Paste" user "Package Geometry/Pastemask Bottom")
		(5 "F.SilkS" user "Ref Des/Silkscreen Top")
		(7 "B.SilkS" user "Ref Des/Silkscreen Bottom")
		(1 "F.Mask" user "Board Geometry/Soldermask Top")
		(3 "B.Mask" user "Board Geometry/Soldermask Bottom")
		(17 "Dwgs.User" user "User.Drawings")
		(19 "Cmts.User" user "User.Comments")
		(21 "Eco1.User" user "User.Eco1")
		(23 "Eco2.User" user "User.Eco2")
		(25 "Edge.Cuts" user "Board Geometry/Outline")
		(27 "Margin" user)
		(31 "F.CrtYd" user "Package Geometry/Place Bound Top")
		(29 "B.CrtYd" user "Package Geometry/Place Bound Bottom")
		(35 "F.Fab" user "Ref Des/Assembly Top")
		(33 "B.Fab" user "Ref Des/Assembly Bottom")
	)
	(footprint ""
		(layer "B.Cu")
		(at 226.366578 -289.828732)
		(property "Reference" "C109"
			(at 0 0 0)
			(layer "B.SilkS")
			(hide yes)
			(effects
				(font
					(size 1.27 1.27)
				)
				(justify mirror)
			)
		)
		(property "Value" ""
			(at 0 0 0)
			(layer "B.Fab")
			(effects
				(font
					(size 1.27 1.27)
				)
				(justify mirror)
			)
		)
		(duplicate_pad_numbers_are_jumpers no)
		(fp_line
			(start -0.7874 -0.4064)
			(end -0.7874 0.4064)
			(stroke
				(width 0.1524)
				(type default)
			)
			(layer "B.SilkS")
		)
		(fp_line
			(start -0.7874 0.4064)
			(end 0.7874 0.4064)
			(stroke
				(width 0.1524)
				(type default)
			)
			(layer "B.SilkS")
		)
		(fp_line
			(start 0.7874 -0.4064)
			(end -0.7874 -0.4064)
			(stroke
				(width 0.1524)
				(type default)
			)
			(layer "B.SilkS")
		)
		(fp_line
			(start 0.7874 0.4064)
			(end 0.7874 -0.4064)
			(stroke
				(width 0.1524)
				(type default)
			)
			(layer "B.SilkS")
		)
		(fp_line
			(start -0.67945 -0.3048)
			(end -0.67945 0.3048)
			(stroke
				(width 0.1)
				(type default)
			)
			(layer "B.Fab")
		)
		(fp_line
			(start -0.67945 0.3048)
			(end -0.120396 0.3048)
			(stroke
				(width 0.1)
				(type default)
			)
			(layer "B.Fab")
		)
		(fp_line
			(start -0.12065 -0.3048)
			(end -0.67945 -0.3048)
			(stroke
				(width 0.1)
				(type default)
			)
			(layer "B.Fab")
		)
		(fp_line
			(start -0.12065 -0.2794)
			(end -0.12065 -0.3048)
			(stroke
				(width 0.1)
				(type default)
			)
			(layer "B.Fab")
		)
		(fp_line
			(start -0.120396 0.2794)
			(end 0.12065 0.2794)
			(stroke
				(width 0.1)
				(type default)
			)
			(layer "B.Fab")
		)
		(fp_line
			(start -0.120396 0.3048)
			(end -0.120396 0.2794)
			(stroke
				(width 0.1)
				(type default)
			)
			(layer "B.Fab")
		)
		(fp_line
			(start 0.12065 -0.305054)
			(end 0.12065 -0.2794)
			(stroke
				(width 0.1)
				(type default)
			)
			(layer "B.Fab")
		)
		(fp_line
			(start 0.12065 -0.2794)
			(end -0.12065 -0.2794)
			(stroke
				(width 0.1)
				(type default)
			)
			(layer "B.Fab")
		)
		(fp_line
			(start 0.12065 0.2794)
			(end 0.12065 0.3048)
			(stroke
				(width 0.1)
				(type default)
			)
			(layer "B.Fab")
		)
		(fp_line
			(start 0.12065 0.3048)
			(end 0.67945 0.3048)
			(stroke
				(width 0.1)
				(type default)
			)
			(layer "B.Fab")
		)
		(fp_line
			(start 0.67945 -0.305054)
			(end 0.12065 -0.305054)
			(stroke
				(width 0.1)
				(type default)
			)
			(layer "B.Fab")
		)
		(fp_line
			(start 0.67945 0.3048)
			(end 0.67945 -0.305054)
			(stroke
				(width 0.1)
				(type default)
			)
			(layer "B.Fab")
		)
		(pad "1" smd circle
			(at 0.40005 0 180)
			(size 0 0)
			(layers "B.Cu" "B.Mask" "B.Paste")
			(net "FM_PWRGD_P1V8_RETIMER_CPU1")
		)
		(pad "2" smd circle
			(at -0.40005 0 180)
			(size 0 0)
			(layers "B.Cu" "B.Mask" "B.Paste")
			(net "GND")
		)
	)
	(footprint ""
		(layer "B.Cu")
		(at 161.595562 -381.11303)
		(property "Reference" "C7026"
			(at 2.78384 3.128772 0)
			(unlocked yes)
			(layer "B.SilkS")
			(effects
				(font
					(size 0.7874 0.5842)
					(thickness 0.1524)
				)
				(justify left mirror)
			)
		)
		(property "Value" ""
			(at 0 0 0)
			(layer "B.Fab")
			(effects
				(font
					(size 1.27 1.27)
				)
				(justify mirror)
			)
		)
		(duplicate_pad_numbers_are_jumpers no)
		(fp_line
			(start -4.53898 -2.15011)
			(end -4.53898 2.15011)
			(stroke
				(width 0.1524)
				(type default)
			)
			(layer "B.SilkS")
		)
		(fp_line
			(start -4.53898 2.15011)
			(end 4.53898 2.15011)
			(stroke
				(width 0.1524)
				(type default)
			)
			(layer "B.SilkS")
		)
		(fp_line
			(start 4.53898 -2.150618)
			(end 4.539742 2.152142)
			(stroke
				(width 0.1524)
				(type default)
			)
			(layer "B.SilkS")
		)
		(fp_line
			(start 4.53898 -2.15011)
			(end -4.53898 -2.15011)
			(stroke
				(width 0.1524)
				(type default)
			)
			(layer "B.SilkS")
		)
		(fp_line
			(start 4.53898 2.15011)
			(end 4.53898 -2.15011)
			(stroke
				(width 0.1524)
				(type default)
			)
			(layer "B.SilkS")
		)
		(fp_line
			(start 4.69138 -2.150618)
			(end 4.692396 2.161032)
			(stroke
				(width 0.1524)
				(type default)
			)
			(layer "B.SilkS")
		)
		(fp_line
			(start 4.83108 2.150364)
			(end 4.447794 2.149348)
			(stroke
				(width 0.1524)
				(type default)
			)
			(layer "B.SilkS")
		)
		(fp_line
			(start 4.84378 -2.150618)
			(end 4.53898 -2.150618)
			(stroke
				(width 0.1524)
				(type default)
			)
			(layer "B.SilkS")
		)
		(fp_line
			(start 4.84378 -2.150618)
			(end 4.842256 2.163064)
			(stroke
				(width 0.1524)
				(type default)
			)
			(layer "B.SilkS")
		)
		(fp_line
			(start -3.64998 -2.15011)
			(end -3.64998 2.15011)
			(stroke
				(width 0.1)
				(type default)
			)
			(layer "B.Fab")
		)
		(fp_line
			(start -3.64998 2.15011)
			(end 3.64998 2.15011)
			(stroke
				(width 0.1)
				(type default)
			)
			(layer "B.Fab")
		)
		(fp_line
			(start 3.64998 -2.15011)
			(end -3.64998 -2.15011)
			(stroke
				(width 0.1)
				(type default)
			)
			(layer "B.Fab")
		)
		(fp_line
			(start 3.64998 2.15011)
			(end 3.64998 -2.15011)
			(stroke
				(width 0.1)
				(type default)
			)
			(layer "B.Fab")
		)
		(fp_text user "-"
			(at -2.568194 2.356612 0)
			(unlocked yes)
			(layer "B.SilkS")
			(effects
				(font
					(size 1.905 1.4224)
					(thickness 0.1524)
				)
				(justify left mirror)
			)
		)
		(fp_text user "+"
			(at 6.214872 -0.337058 0)
			(unlocked yes)
			(layer "B.SilkS")
			(effects
				(font
					(size 1.905 1.4224)
					(thickness 0.1524)
				)
				(justify left mirror)
			)
		)
		(fp_text user "-"
			(at -4.313174 -0.094488 0)
			(unlocked yes)
			(layer "B.Fab")
			(effects
				(font
					(size 1.905 1.4224)
					(thickness 0.1524)
				)
				(justify left mirror)
			)
		)
		(fp_text user "+"
			(at 6.214872 -0.337058 0)
			(unlocked yes)
			(layer "B.Fab")
			(effects
				(font
					(size 1.905 1.4224)
					(thickness 0.1524)
				)
				(justify left mirror)
			)
		)
		(pad "1" smd rect
			(at 3.199892 0 180)
			(size 2.413 2.8194)
			(layers "B.Cu" "B.Mask" "B.Paste")
			(net "P0V9_CPU1_RT2_2A")
		)
		(pad "2" smd rect
			(at -3.199892 0 180)
			(size 2.413 2.8194)
			(layers "B.Cu" "B.Mask" "B.Paste")
			(net "GND")
		)
	)
)
